# HDD Back Plane_Stackup.xlsx — Stackup (pcb-stackup)
|  |  |  |  |  |  |  | Version |  |  |  |  |  |  |  |  |  |  |  |  |  |  |  |
|  |  | Board Number: | 17301-SA |  |  |  | 1 |  |  |  |  |  |  |  |  |  |  |  |  |  |  |  |
|  |  | Project Name: | Tioga Pass Channel |  |  |  |  |  |  |  |  |  |  |  |  |  |  |  |  |  |  |  |
|  |  | Model Name: | HDD Back Palnee |  |  |  |  |  |  |  |  |  |  |  |  |  |  |  |  |  |  |  |
|  |  | Layer Count: | 6 Layer |  |  |  |  |  |  |  |  |  |  |  |  |  |  |  |  |  |  |  |
|  |  | Date: | 2017-06-13 00:00:00 |  |  |  |  |  |  |  |  |  |  |  |  |  |  |  |  |  |  |  |
|  |  | Middle Loss Material: | IT170GRA1 / NPG171 |  |  |  |  |  |  |  |  | Single Ended Impedance (ohm) |  |  |  |  | Differential Impedance (ohm) |  |  |  |  |  |
|  |  | Gold Finger (Y/N): | No |  |  |  |  |  |  |  | Imp | 50 |  |  |  | Imp | 85 |  |  |  |  |  |
|  |  | Customer/Type: | N/A |  |  |  |  |  |  |  | Variation | Inner/Outer+/-5ohm |  |  |  | Variation | Inner/Outer+/-10% |  |  |  |  |  |
|  |  | EE Engineer: | <name> |  |  |  |  |  |  |  | Bus | MISC. / I2C |  |  |  | Bus | PCIe / Clock |  |  |  |  |  |
|  |  | SI Engineer: | <name> |  |  |  |  |  |  |  |  |  |  |  |  |  |  |  |  |  |  |  |
|  |  |  |  |  |  |  |  |  |  |  | Type | SE |  |  |  | Type | DP |  |  |  |  |  |
| Layer |  |  | Cu Weight | Thickness |  | Glass/Copper Type | Er (1GHz) |  | Df (1GHz) |  | Layers | 1,3,4,6 |  |  |  | Layers | 1,3,4,6 |  |  |  |  |  |
|  |  |  | Wiwynn/Vendor | Wiwynn | Vendor | Wiwynn/Vendor | Wiwynn | Vendor | Wiwynn | Vendor |  | Wiwynn |  | Vendor |  |  | Wiwynn |  |  | Vendor |  |  |
|  | Mask |  |  | 0.5 |  |  | 3.8 |  |  |  |  | Width | Imp | Width | Imp |  | Width | Space | Imp | Width | Space | Imp |
| Top | Signal |  | 0.5 oz + plating | 1.9 |  |  |  |  |  |  | S1 | 7.2(L2) |  |  |  | S1 | 8.4(L2) | 9 |  |  |  |  |
|  | Prepreg |  |  | 4 |  |  | 3.7 |  |  |  |  |  |  |  |  |  |  |  |  |  |  |  |
| L2 | Ground |  | 1.0 oz | 1.3 |  |  |  |  |  |  | P2 | reference layer |  |  |  | P2 | reference layer |  |  |  |  |  |
|  | Core |  |  | 4 |  |  | 3.7 |  |  |  |  |  |  |  |  |  |  |  |  |  |  |  |
| L3 | Signal |  | 1.0 oz | 1.3 |  |  |  |  |  |  | S3 | 5.7(L2/L5) |  |  |  | S3 | 5.6(L2/L5) | 7 |  |  |  |  |
|  | Prepreg |  |  | 53 |  |  | 4.1 |  |  |  |  |  |  |  |  |  |  |  |  |  |  |  |
| L4 | Signal |  | 1.0 oz | 1.3 |  |  |  |  |  |  | S4 | 5.7(L2/L5) |  |  |  | S4 | 5.6(L2/L5) | 7 |  |  |  |  |
|  | Core |  |  | 4 |  |  | 3.7 |  |  |  |  |  |  |  |  |  |  |  |  |  |  |  |
| L5 | Ground |  | 1.0 oz | 1.3 |  |  |  |  |  |  | P5 | reference layer |  |  |  | P5 | reference layer |  |  |  |  |  |
|  | Prepreg |  |  | 4 |  |  | 3.7 |  |  |  |  |  |  |  |  |  |  |  |  |  |  |  |
| Bottom | Signal |  | 0.5 oz + plating | 1.9 |  |  |  |  |  |  | S6 | 7.2(L5) |  |  |  | S6 | 8.4(L5) | 9 |  |  |  |  |
|  | Mask |  |  | 0.5 |  |  | 3.8 |  |  |  |  |  |  |  |  |  |  |  |  |  |  |  |
| Thickness requirement: 2.01 ± 10% mm |  |  | mil | 79 |  |  |  |  |  |  |  |  |  |  |  |  |  |  |  |  |  |  |
|  |  |  | mm | 2.006599999999999 |  |  |  |  |  |  |  |  |  |  |  |  |  |  |  |  |  |  |
| Note: | 1. Unit is mil |  |  |  |  |  |  |  |  |  |  |  |  |  |  |  |  |  |  |  |  |  |
|  | 2. The total thickness includes trace and solder mask. |  |  |  |  |  |  |  |  |  |  |  |  |  |  |  |  |  |  |  |  |  |
|  | 3. Minimum hole copper thickness is 1.0 mil. |  |  |  |  |  |  |  |  |  |  |  |  |  |  |  |  |  |  |  |  |  |
|  | 4. Minimum surface copper thickness 1.5 mil. |  |  |  |  |  |  |  |  |  |  |  |  |  |  |  |  |  |  |  |  |  |
|  | 5. If there is no controlled impedance line described as the stackup in the gerber file, PCB supplier can ignore this kind of impedance control directly, but need to inform Wiwynn in engineering question(EQ). |  |  |  |  |  |  |  |  |  |  |  |  |  |  |  |  |  |  |  |  |  |
|  | 6. PCB test coupon requirement and PCB test note are described in the another sheets. |  |  |  |  |  |  |  |  |  |  |  |  |  |  |  |  |  |  |  |  |  |
|  | 7. If there is no "Delta-L" design in gerber file, PCB supplier should design 85 ohm "Delta-L" angle routing coupon and provide the measurement results in FAI report which meet the following criteria: |  |  |  |  |  |  |  |  |  |  |  |  |  |  |  |  |  |  |  |  |  |
|  | 8. Solder mask color information : POC(FA) : Red; EVT(SA) : Blue; DVT(1A) : Yellow; PVT(1B) : Green; MP(1) : Green. |  |  |  |  |  |  |  |  |  |  |  |  |  |  |  |  |  |  |  |  |  |
|  | For middle-loss material |  |  |  |  |  |  |  |  |  |  |  |  |  |  |  |  |  |  |  |  |  |
|  | (1)   0.69 dB/inch @ 4GHz; 1.38 dB/inch @ 8GHz for microstrip routing |  |  |  |  |  |  |  |  |  |  |  |  |  |  |  |  |  |  |  |  |  |
|  | (2)   0.65 dB/inch @ 4GHz; 1.25 dB/inch @ 8GHz for stripline routing |  |  |  |  |  |  |  |  |  |  |  |  |  |  |  |  |  |  |  |  |  |
|  |  | For standard-loss material |  |  |  |  |  |  |  |  |  |  |  |  |  |  |  |  |  |  |  |  |
|  |  | (1)   0.79 dB/inch @ 4GHz; 1.58 dB/inch @ 8GHz for microstrip routing |  |  |  |  |  |  |  |  |  |  |  |  |  |  |  |  |  |  |  |  |
|  |  | (2)   0.75 dB/inch @ 4GHz; 1.5 dB/inch @ 8GHz for stripline routing |  |  |  |  |  |  |  |  |  |  |  |  |  |  |  |  |  |  |  |  |
|  |  | For middle-loss material |  |  |  |  |  |  |  |  |  |  |  |  |  |  |  |  |  |  |  |  |
|  |  | (1)   0.69 dB/inch @ 4GHz; 1.38 dB/inch @ 8GHz for microstrip routing |  |  |  |  |  |  |  |  |  |  |  |  |  |  |  |  |  |  |  |  |
|  |  | (2)   0.65 dB/inch @ 4GHz; 1.25 dB/inch @ 8GHz for stripline routing |  |  |  |  |  |  |  |  |  |  |  |  |  |  |  |  |  |  |  |  |
|  |  | For low-loss material |  |  |  |  |  |  |  |  |  |  |  |  |  |  |  |  |  |  |  |  |
|  |  | (1)   0.55 dB/inch @ 4GHz; 1.05 dB/inch @ 8GHz for microstrip routing |  |  |  |  |  |  |  |  |  |  |  |  |  |  |  |  |  |  |  |  |
|  |  | (2)   0.48 dB/inch @ 4GHz; 0.9 dB/inch @ 8GHz for stripline routing |  |  |  |  |  |  |  |  |  |  |  |  |  |  |  |  |  |  |  |  |
